# T6G (Grand Teton) — schematic netlist excerpt (pin names and nets, part order shuffled) for the footprints in the layout excerpt that follows; sources: Cadence DE-HDL packaged netlist, KiCad conversion of 04192023_DAF0TMB3IC0_F0TG_MB_C_brd_V02_OCP.brd

R1737  Q_RES  0 5% CHIP  pkg 0402LF  page 171 : A = JTAG_SCM_MUX_R_TMS ; B = JTAG_SCM_MUX_TMS
R5487  Q_RES  0 5% EMPTY  pkg 0402LF  page 134 : A = P3V3_OCP_SFF_EN_R ; B = P3V3_OCP_EN_1_R

(kicad_pcb
	(version 20260206)
	(generator "pcbnew")
	(generator_version "10.0")
	(general
		(thickness 1.6)
		(legacy_teardrops no)
	)
	(paper "A4")
	(title_block
		(title "04192023_DAF0TMB3IC0_F0TG_MB_C_brd_V02_OCP.brd")
		(comment 1 "Grand Teton / footprints 2051-2052 of 8354")
	)
	(layers
		(0 "F.Cu" signal "TOP")
		(4 "In1.Cu" signal "GND")
		(6 "In2.Cu" signal "IN1")
		(8 "In3.Cu" signal "GND1")
		(10 "In4.Cu" signal "IN2")
		(12 "In5.Cu" signal "GND2")
		(14 "In6.Cu" signal "IN3")
		(16 "In7.Cu" signal "GND3")
		(18 "In8.Cu" signal "VCC")
		(20 "In9.Cu" signal "VCC1")
		(22 "In10.Cu" signal "GND4")
		(24 "In11.Cu" signal "IN4")
		(26 "In12.Cu" signal "GND5")
		(28 "In13.Cu" signal "IN5")
		(30 "In14.Cu" signal "GND6")
		(32 "In15.Cu" signal "IN6")
		(34 "In16.Cu" signal "GND7")
		(2 "B.Cu" signal "BOTTOM")
		(9 "F.Adhes" user "F.Adhesive")
		(11 "B.Adhes" user "B.Adhesive")
		(13 "F.Paste" user "Package Geometry/Pastemask Top")
		(15 "B.Paste" user "Package Geometry/Pastemask Bottom")
		(5 "F.SilkS" user "Ref Des/Silkscreen Top")
		(7 "B.SilkS" user "Ref Des/Silkscreen Bottom")
		(1 "F.Mask" user "Board Geometry/Soldermask Top")
		(3 "B.Mask" user "Board Geometry/Soldermask Bottom")
		(17 "Dwgs.User" user "User.Drawings")
		(19 "Cmts.User" user "User.Comments")
		(21 "Eco1.User" user "User.Eco1")
		(23 "Eco2.User" user "User.Eco2")
		(25 "Edge.Cuts" user "Board Geometry/Outline")
		(27 "Margin" user)
		(31 "F.CrtYd" user "Package Geometry/Place Bound Top")
		(29 "B.CrtYd" user "Package Geometry/Place Bound Bottom")
		(35 "F.Fab" user "Ref Des/Assembly Top")
		(33 "B.Fab" user "Ref Des/Assembly Bottom")
	)
	(footprint ""
		(layer "F.Cu")
		(at 105.64876 -58.502042 180)
		(property "Reference" "R1737"
			(at 0 0 180)
			(layer "F.SilkS")
			(hide yes)
			(effects
				(font
					(size 1.27 1.27)
				)
			)
		)
		(property "Value" ""
			(at 0 0 180)
			(layer "F.Fab")
			(effects
				(font
					(size 1.27 1.27)
				)
			)
		)
		(duplicate_pad_numbers_are_jumpers no)
		(fp_line
			(start 0.7874 0.4064)
			(end -0.7874 0.4064)
			(stroke
				(width 0.1524)
				(type default)
			)
			(layer "F.SilkS")
		)
		(fp_line
			(start 0.7874 -0.4064)
			(end 0.7874 0.4064)
			(stroke
				(width 0.1524)
				(type default)
			)
			(layer "F.SilkS")
		)
		(fp_line
			(start -0.7874 0.4064)
			(end -0.7874 -0.4064)
			(stroke
				(width 0.1524)
				(type default)
			)
			(layer "F.SilkS")
		)
		(fp_line
			(start -0.7874 -0.4064)
			(end 0.7874 -0.4064)
			(stroke
				(width 0.1524)
				(type default)
			)
			(layer "F.SilkS")
		)
		(fp_line
			(start 0.67945 0.3048)
			(end 0.120396 0.3048)
			(stroke
				(width 0.1)
				(type default)
			)
			(layer "F.Fab")
		)
		(fp_line
			(start 0.67945 -0.3048)
			(end 0.67945 0.3048)
			(stroke
				(width 0.1)
				(type default)
			)
			(layer "F.Fab")
		)
		(fp_line
			(start 0.12065 -0.2794)
			(end 0.12065 -0.3048)
			(stroke
				(width 0.1)
				(type default)
			)
			(layer "F.Fab")
		)
		(fp_line
			(start 0.12065 -0.3048)
			(end 0.67945 -0.3048)
			(stroke
				(width 0.1)
				(type default)
			)
			(layer "F.Fab")
		)
		(fp_line
			(start 0.120396 0.3048)
			(end 0.120396 0.2794)
			(stroke
				(width 0.1)
				(type default)
			)
			(layer "F.Fab")
		)
		(fp_line
			(start 0.120396 0.2794)
			(end -0.12065 0.2794)
			(stroke
				(width 0.1)
				(type default)
			)
			(layer "F.Fab")
		)
		(fp_line
			(start -0.12065 0.3048)
			(end -0.67945 0.3048)
			(stroke
				(width 0.1)
				(type default)
			)
			(layer "F.Fab")
		)
		(fp_line
			(start -0.12065 0.2794)
			(end -0.12065 0.3048)
			(stroke
				(width 0.1)
				(type default)
			)
			(layer "F.Fab")
		)
		(fp_line
			(start -0.12065 -0.2794)
			(end 0.12065 -0.2794)
			(stroke
				(width 0.1)
				(type default)
			)
			(layer "F.Fab")
		)
		(fp_line
			(start -0.12065 -0.305054)
			(end -0.12065 -0.2794)
			(stroke
				(width 0.1)
				(type default)
			)
			(layer "F.Fab")
		)
		(fp_line
			(start -0.67945 0.3048)
			(end -0.67945 -0.305054)
			(stroke
				(width 0.1)
				(type default)
			)
			(layer "F.Fab")
		)
		(fp_line
			(start -0.67945 -0.305054)
			(end -0.12065 -0.305054)
			(stroke
				(width 0.1)
				(type default)
			)
			(layer "F.Fab")
		)
		(pad "1" smd circle
			(at -0.40005 0 180)
			(size 0 0)
			(layers "F.Cu" "F.Mask" "F.Paste")
			(net "JTAG_SCM_MUX_R_TMS")
		)
		(pad "2" smd circle
			(at 0.40005 0 180)
			(size 0 0)
			(layers "F.Cu" "F.Mask" "F.Paste")
			(net "JTAG_SCM_MUX_TMS")
		)
	)
	(footprint ""
		(layer "F.Cu")
		(at 455.01306 -42.121836)
		(property "Reference" "R5487"
			(at 0 0 0)
			(layer "F.SilkS")
			(hide yes)
			(effects
				(font
					(size 1.27 1.27)
				)
			)
		)
		(property "Value" ""
			(at 0 0 0)
			(layer "F.Fab")
			(effects
				(font
					(size 1.27 1.27)
				)
			)
		)
		(duplicate_pad_numbers_are_jumpers no)
		(fp_line
			(start -0.7874 -0.4064)
			(end 0.7874 -0.4064)
			(stroke
				(width 0.1524)
				(type default)
			)
			(layer "F.SilkS")
		)
		(fp_line
			(start -0.7874 0.4064)
			(end -0.7874 -0.4064)
			(stroke
				(width 0.1524)
				(type default)
			)
			(layer "F.SilkS")
		)
		(fp_line
			(start 0.7874 -0.4064)
			(end 0.7874 0.4064)
			(stroke
				(width 0.1524)
				(type default)
			)
			(layer "F.SilkS")
		)
		(fp_line
			(start 0.7874 0.4064)
			(end -0.7874 0.4064)
			(stroke
				(width 0.1524)
				(type default)
			)
			(layer "F.SilkS")
		)
		(fp_line
			(start -0.67945 -0.305054)
			(end -0.12065 -0.305054)
			(stroke
				(width 0.1)
				(type default)
			)
			(layer "F.Fab")
		)
		(fp_line
			(start -0.67945 0.3048)
			(end -0.67945 -0.305054)
			(stroke
				(width 0.1)
				(type default)
			)
			(layer "F.Fab")
		)
		(fp_line
			(start -0.12065 -0.305054)
			(end -0.12065 -0.2794)
			(stroke
				(width 0.1)
				(type default)
			)
			(layer "F.Fab")
		)
		(fp_line
			(start -0.12065 -0.2794)
			(end 0.12065 -0.2794)
			(stroke
				(width 0.1)
				(type default)
			)
			(layer "F.Fab")
		)
		(fp_line
			(start -0.12065 0.2794)
			(end -0.12065 0.3048)
			(stroke
				(width 0.1)
				(type default)
			)
			(layer "F.Fab")
		)
		(fp_line
			(start -0.12065 0.3048)
			(end -0.67945 0.3048)
			(stroke
				(width 0.1)
				(type default)
			)
			(layer "F.Fab")
		)
		(fp_line
			(start 0.120396 0.2794)
			(end -0.12065 0.2794)
			(stroke
				(width 0.1)
				(type default)
			)
			(layer "F.Fab")
		)
		(fp_line
			(start 0.120396 0.3048)
			(end 0.120396 0.2794)
			(stroke
				(width 0.1)
				(type default)
			)
			(layer "F.Fab")
		)
		(fp_line
			(start 0.12065 -0.3048)
			(end 0.67945 -0.3048)
			(stroke
				(width 0.1)
				(type default)
			)
			(layer "F.Fab")
		)
		(fp_line
			(start 0.12065 -0.2794)
			(end 0.12065 -0.3048)
			(stroke
				(width 0.1)
				(type default)
			)
			(layer "F.Fab")
		)
		(fp_line
			(start 0.67945 -0.3048)
			(end 0.67945 0.3048)
			(stroke
				(width 0.1)
				(type default)
			)
			(layer "F.Fab")
		)
		(fp_line
			(start 0.67945 0.3048)
			(end 0.120396 0.3048)
			(stroke
				(width 0.1)
				(type default)
			)
			(layer "F.Fab")
		)
		(pad "1" smd circle
			(at -0.40005 0)
			(size 0 0)
			(layers "F.Cu" "F.Mask" "F.Paste")
			(net "P3V3_OCP_SFF_EN_R")
		)
		(pad "2" smd circle
			(at 0.40005 0)
			(size 0 0)
			(layers "F.Cu" "F.Mask" "F.Paste")
			(net "P3V3_OCP_EN_1_R")
		)
	)
)
